FILE_TYPE = CONNECTIVITY;
{Allegro Design Entry HDL 17.2-2016 S081 (4005846) 1/11/2022}
"PAGE_NUMBER" = 172;
0"NC";
END.
